# T6G (Grand Teton) — schematic netlist excerpt (pin names and nets, part order shuffled) for the footprints in the layout excerpt that follows; sources: Cadence DE-HDL packaged netlist, KiCad conversion of 04192023_DAF0TMB3IC0_F0TG_MB_C_brd_V02_OCP.brd

C8018  Q_CAP  100NF 50V 10% EMPTY  pkg C0402  page 268 : A = P12V_AUX_UV_ADR_TRIGGER ; B = GND
R349  Q_RES  33 5% CHIP  pkg 0402LF  page 151 : A = SMB_SCM_2_R2_SCL ; B = SMB_SCM_2_R5_SCL

(kicad_pcb
	(version 20260206)
	(generator "pcbnew")
	(generator_version "10.0")
	(general
		(thickness 1.6)
		(legacy_teardrops no)
	)
	(paper "A4")
	(title_block
		(title "04192023_DAF0TMB3IC0_F0TG_MB_C_brd_V02_OCP.brd")
		(comment 1 "Grand Teton / footprints 1775-1776 of 8354")
	)
	(layers
		(0 "F.Cu" signal "TOP")
		(4 "In1.Cu" signal "GND")
		(6 "In2.Cu" signal "IN1")
		(8 "In3.Cu" signal "GND1")
		(10 "In4.Cu" signal "IN2")
		(12 "In5.Cu" signal "GND2")
		(14 "In6.Cu" signal "IN3")
		(16 "In7.Cu" signal "GND3")
		(18 "In8.Cu" signal "VCC")
		(20 "In9.Cu" signal "VCC1")
		(22 "In10.Cu" signal "GND4")
		(24 "In11.Cu" signal "IN4")
		(26 "In12.Cu" signal "GND5")
		(28 "In13.Cu" signal "IN5")
		(30 "In14.Cu" signal "GND6")
		(32 "In15.Cu" signal "IN6")
		(34 "In16.Cu" signal "GND7")
		(2 "B.Cu" signal "BOTTOM")
		(9 "F.Adhes" user "F.Adhesive")
		(11 "B.Adhes" user "B.Adhesive")
		(13 "F.Paste" user "Package Geometry/Pastemask Top")
		(15 "B.Paste" user "Package Geometry/Pastemask Bottom")
		(5 "F.SilkS" user "Ref Des/Silkscreen Top")
		(7 "B.SilkS" user "Ref Des/Silkscreen Bottom")
		(1 "F.Mask" user "Board Geometry/Soldermask Top")
		(3 "B.Mask" user "Board Geometry/Soldermask Bottom")
		(17 "Dwgs.User" user "User.Drawings")
		(19 "Cmts.User" user "User.Comments")
		(21 "Eco1.User" user "User.Eco1")
		(23 "Eco2.User" user "User.Eco2")
		(25 "Edge.Cuts" user "Board Geometry/Outline")
		(27 "Margin" user)
		(31 "F.CrtYd" user "Package Geometry/Place Bound Top")
		(29 "B.CrtYd" user "Package Geometry/Place Bound Bottom")
		(35 "F.Fab" user "Ref Des/Assembly Top")
		(33 "B.Fab" user "Ref Des/Assembly Bottom")
	)
	(footprint ""
		(layer "F.Cu")
		(at 131.699 -109.474 -90)
		(property "Reference" "C8018"
			(at 0 0 270)
			(layer "F.SilkS")
			(hide yes)
			(effects
				(font
					(size 1.27 1.27)
				)
			)
		)
		(property "Value" ""
			(at 0 0 270)
			(layer "F.Fab")
			(effects
				(font
					(size 1.27 1.27)
				)
			)
		)
		(duplicate_pad_numbers_are_jumpers no)
		(fp_line
			(start -0.7874 0.4064)
			(end -0.7874 -0.4064)
			(stroke
				(width 0.1524)
				(type default)
			)
			(layer "F.SilkS")
		)
		(fp_line
			(start 0.7874 0.4064)
			(end -0.7874 0.4064)
			(stroke
				(width 0.1524)
				(type default)
			)
			(layer "F.SilkS")
		)
		(fp_line
			(start -0.7874 -0.4064)
			(end 0.7874 -0.4064)
			(stroke
				(width 0.1524)
				(type default)
			)
			(layer "F.SilkS")
		)
		(fp_line
			(start 0.7874 -0.4064)
			(end 0.7874 0.4064)
			(stroke
				(width 0.1524)
				(type default)
			)
			(layer "F.SilkS")
		)
		(fp_line
			(start -0.67945 0.3048)
			(end -0.67945 -0.305054)
			(stroke
				(width 0.1)
				(type default)
			)
			(layer "F.Fab")
		)
		(fp_line
			(start -0.12065 0.3048)
			(end -0.67945 0.3048)
			(stroke
				(width 0.1)
				(type default)
			)
			(layer "F.Fab")
		)
		(fp_line
			(start 0.120396 0.3048)
			(end 0.120396 0.2794)
			(stroke
				(width 0.1)
				(type default)
			)
			(layer "F.Fab")
		)
		(fp_line
			(start 0.67945 0.3048)
			(end 0.120396 0.3048)
			(stroke
				(width 0.1)
				(type default)
			)
			(layer "F.Fab")
		)
		(fp_line
			(start -0.12065 0.2794)
			(end -0.12065 0.3048)
			(stroke
				(width 0.1)
				(type default)
			)
			(layer "F.Fab")
		)
		(fp_line
			(start 0.120396 0.2794)
			(end -0.12065 0.2794)
			(stroke
				(width 0.1)
				(type default)
			)
			(layer "F.Fab")
		)
		(fp_line
			(start -0.12065 -0.2794)
			(end 0.12065 -0.2794)
			(stroke
				(width 0.1)
				(type default)
			)
			(layer "F.Fab")
		)
		(fp_line
			(start 0.12065 -0.2794)
			(end 0.12065 -0.3048)
			(stroke
				(width 0.1)
				(type default)
			)
			(layer "F.Fab")
		)
		(fp_line
			(start 0.12065 -0.3048)
			(end 0.67945 -0.3048)
			(stroke
				(width 0.1)
				(type default)
			)
			(layer "F.Fab")
		)
		(fp_line
			(start 0.67945 -0.3048)
			(end 0.67945 0.3048)
			(stroke
				(width 0.1)
				(type default)
			)
			(layer "F.Fab")
		)
		(fp_line
			(start -0.67945 -0.305054)
			(end -0.12065 -0.305054)
			(stroke
				(width 0.1)
				(type default)
			)
			(layer "F.Fab")
		)
		(fp_line
			(start -0.12065 -0.305054)
			(end -0.12065 -0.2794)
			(stroke
				(width 0.1)
				(type default)
			)
			(layer "F.Fab")
		)
		(pad "1" smd circle
			(at -0.40005 0 270)
			(size 0 0)
			(layers "F.Cu" "F.Mask" "F.Paste")
			(net "P12V_AUX_UV_ADR_TRIGGER")
		)
		(pad "2" smd circle
			(at 0.40005 0 270)
			(size 0 0)
			(layers "F.Cu" "F.Mask" "F.Paste")
			(net "GND")
		)
	)
	(footprint ""
		(layer "F.Cu")
		(at 160.02 -356.362 90)
		(property "Reference" "R349"
			(at 0 0 90)
			(layer "F.SilkS")
			(hide yes)
			(effects
				(font
					(size 1.27 1.27)
				)
			)
		)
		(property "Value" ""
			(at 0 0 90)
			(layer "F.Fab")
			(effects
				(font
					(size 1.27 1.27)
				)
			)
		)
		(duplicate_pad_numbers_are_jumpers no)
		(fp_line
			(start 0.7874 -0.4064)
			(end 0.7874 0.4064)
			(stroke
				(width 0.1524)
				(type default)
			)
			(layer "F.SilkS")
		)
		(fp_line
			(start -0.7874 -0.4064)
			(end 0.7874 -0.4064)
			(stroke
				(width 0.1524)
				(type default)
			)
			(layer "F.SilkS")
		)
		(fp_line
			(start 0.7874 0.4064)
			(end -0.7874 0.4064)
			(stroke
				(width 0.1524)
				(type default)
			)
			(layer "F.SilkS")
		)
		(fp_line
			(start -0.7874 0.4064)
			(end -0.7874 -0.4064)
			(stroke
				(width 0.1524)
				(type default)
			)
			(layer "F.SilkS")
		)
		(fp_line
			(start -0.12065 -0.305054)
			(end -0.12065 -0.2794)
			(stroke
				(width 0.1)
				(type default)
			)
			(layer "F.Fab")
		)
		(fp_line
			(start -0.67945 -0.305054)
			(end -0.12065 -0.305054)
			(stroke
				(width 0.1)
				(type default)
			)
			(layer "F.Fab")
		)
		(fp_line
			(start 0.67945 -0.3048)
			(end 0.67945 0.3048)
			(stroke
				(width 0.1)
				(type default)
			)
			(layer "F.Fab")
		)
		(fp_line
			(start 0.12065 -0.3048)
			(end 0.67945 -0.3048)
			(stroke
				(width 0.1)
				(type default)
			)
			(layer "F.Fab")
		)
		(fp_line
			(start 0.12065 -0.2794)
			(end 0.12065 -0.3048)
			(stroke
				(width 0.1)
				(type default)
			)
			(layer "F.Fab")
		)
		(fp_line
			(start -0.12065 -0.2794)
			(end 0.12065 -0.2794)
			(stroke
				(width 0.1)
				(type default)
			)
			(layer "F.Fab")
		)
		(fp_line
			(start 0.120396 0.2794)
			(end -0.12065 0.2794)
			(stroke
				(width 0.1)
				(type default)
			)
			(layer "F.Fab")
		)
		(fp_line
			(start -0.12065 0.2794)
			(end -0.12065 0.3048)
			(stroke
				(width 0.1)
				(type default)
			)
			(layer "F.Fab")
		)
		(fp_line
			(start 0.67945 0.3048)
			(end 0.120396 0.3048)
			(stroke
				(width 0.1)
				(type default)
			)
			(layer "F.Fab")
		)
		(fp_line
			(start 0.120396 0.3048)
			(end 0.120396 0.2794)
			(stroke
				(width 0.1)
				(type default)
			)
			(layer "F.Fab")
		)
		(fp_line
			(start -0.12065 0.3048)
			(end -0.67945 0.3048)
			(stroke
				(width 0.1)
				(type default)
			)
			(layer "F.Fab")
		)
		(fp_line
			(start -0.67945 0.3048)
			(end -0.67945 -0.305054)
			(stroke
				(width 0.1)
				(type default)
			)
			(layer "F.Fab")
		)
		(pad "1" smd circle
			(at -0.40005 0 90)
			(size 0 0)
			(layers "F.Cu" "F.Mask" "F.Paste")
			(net "SMB_SCM_2_R2_SCL")
		)
		(pad "2" smd circle
			(at 0.40005 0 90)
			(size 0 0)
			(layers "F.Cu" "F.Mask" "F.Paste")
			(net "SMB_SCM_2_R5_SCL")
		)
	)
)
